(kicad_pcb
	(version 20260206)
	(generator "pcbnew")
	(generator_version "10.0")
	(general
		(thickness 1.6)
		(legacy_teardrops no)
	)
	(paper "A4")
	(title_block
		(title "01162023_DA0F0TEBIF0_F0T_Expander_BD_F_brd_V02_OCP.brd")
		(comment 1 "Grand Teton / footprints 4289-4294 of 9728")
	)
	(layers
		(0 "F.Cu" signal "TOP")
		(4 "In1.Cu" signal "GND")
		(6 "In2.Cu" signal "VCC")
		(8 "In3.Cu" signal "VCC1")
		(10 "In4.Cu" signal "GND1")
		(12 "In5.Cu" signal "IN1")
		(14 "In6.Cu" signal "GND2")
		(16 "In7.Cu" signal "IN2")
		(18 "In8.Cu" signal "GND3")
		(20 "In9.Cu" signal "IN3")
		(22 "In10.Cu" signal "GND4")
		(24 "In11.Cu" signal "IN4")
		(26 "In12.Cu" signal "GND5")
		(28 "In13.Cu" signal "IN5")
		(30 "In14.Cu" signal "GND6")
		(32 "In15.Cu" signal "IN6")
		(34 "In16.Cu" signal "GND7")
		(2 "B.Cu" signal "BOTTOM")
		(9 "F.Adhes" user "F.Adhesive")
		(11 "B.Adhes" user "B.Adhesive")
		(13 "F.Paste" user "Package Geometry/Pastemask Top")
		(15 "B.Paste" user "Package Geometry/Pastemask Bottom")
		(5 "F.SilkS" user "Ref Des/Silkscreen Top")
		(7 "B.SilkS" user "Ref Des/Silkscreen Bottom")
		(1 "F.Mask" user "Board Geometry/Soldermask Top")
		(3 "B.Mask" user "Board Geometry/Soldermask Bottom")
		(17 "Dwgs.User" user "User.Drawings")
		(19 "Cmts.User" user "User.Comments")
		(21 "Eco1.User" user "User.Eco1")
		(23 "Eco2.User" user "User.Eco2")
		(25 "Edge.Cuts" user "Board Geometry/Outline")
		(27 "Margin" user)
		(31 "F.CrtYd" user "Package Geometry/Place Bound Top")
		(29 "B.CrtYd" user "Package Geometry/Place Bound Bottom")
		(35 "F.Fab" user "Ref Des/Assembly Top")
		(33 "B.Fab" user "Ref Des/Assembly Bottom")
	)
	(footprint ""
		(layer "F.Cu")
		(at 415.057082 -197.155308 -90)
		(property "Reference" "R6428"
			(at 0 0 270)
			(layer "F.SilkS")
			(hide yes)
			(effects
				(font
					(size 1.27 1.27)
				)
			)
		)
		(property "Value" ""
			(at 0 0 270)
			(layer "F.Fab")
			(effects
				(font
					(size 1.27 1.27)
				)
			)
		)
		(duplicate_pad_numbers_are_jumpers no)
		(fp_line
			(start -0.7874 0.4064)
			(end -0.7874 -0.4064)
			(stroke
				(width 0.1524)
				(type default)
			)
			(layer "F.SilkS")
		)
		(fp_line
			(start 0.7874 0.4064)
			(end -0.7874 0.4064)
			(stroke
				(width 0.1524)
				(type default)
			)
			(layer "F.SilkS")
		)
		(fp_line
			(start -0.7874 -0.4064)
			(end 0.7874 -0.4064)
			(stroke
				(width 0.1524)
				(type default)
			)
			(layer "F.SilkS")
		)
		(fp_line
			(start 0.7874 -0.4064)
			(end 0.7874 0.4064)
			(stroke
				(width 0.1524)
				(type default)
			)
			(layer "F.SilkS")
		)
		(fp_line
			(start -0.67945 0.3048)
			(end -0.67945 -0.305054)
			(stroke
				(width 0.1)
				(type default)
			)
			(layer "F.Fab")
		)
		(fp_line
			(start -0.12065 0.3048)
			(end -0.67945 0.3048)
			(stroke
				(width 0.1)
				(type default)
			)
			(layer "F.Fab")
		)
		(fp_line
			(start 0.120396 0.3048)
			(end 0.120396 0.2794)
			(stroke
				(width 0.1)
				(type default)
			)
			(layer "F.Fab")
		)
		(fp_line
			(start 0.67945 0.3048)
			(end 0.120396 0.3048)
			(stroke
				(width 0.1)
				(type default)
			)
			(layer "F.Fab")
		)
		(fp_line
			(start -0.12065 0.2794)
			(end -0.12065 0.3048)
			(stroke
				(width 0.1)
				(type default)
			)
			(layer "F.Fab")
		)
		(fp_line
			(start 0.120396 0.2794)
			(end -0.12065 0.2794)
			(stroke
				(width 0.1)
				(type default)
			)
			(layer "F.Fab")
		)
		(fp_line
			(start -0.12065 -0.2794)
			(end 0.12065 -0.2794)
			(stroke
				(width 0.1)
				(type default)
			)
			(layer "F.Fab")
		)
		(fp_line
			(start 0.12065 -0.2794)
			(end 0.12065 -0.3048)
			(stroke
				(width 0.1)
				(type default)
			)
			(layer "F.Fab")
		)
		(fp_line
			(start 0.12065 -0.3048)
			(end 0.67945 -0.3048)
			(stroke
				(width 0.1)
				(type default)
			)
			(layer "F.Fab")
		)
		(fp_line
			(start 0.67945 -0.3048)
			(end 0.67945 0.3048)
			(stroke
				(width 0.1)
				(type default)
			)
			(layer "F.Fab")
		)
		(fp_line
			(start -0.67945 -0.305054)
			(end -0.12065 -0.305054)
			(stroke
				(width 0.1)
				(type default)
			)
			(layer "F.Fab")
		)
		(fp_line
			(start -0.12065 -0.305054)
			(end -0.12065 -0.2794)
			(stroke
				(width 0.1)
				(type default)
			)
			(layer "F.Fab")
		)
		(pad "1" smd circle
			(at -0.40005 0 270)
			(size 0 0)
			(layers "F.Cu" "F.Mask" "F.Paste")
			(net "FPGA_PEX0_MODE_SEL1_D_N")
		)
		(pad "2" smd circle
			(at 0.40005 0 270)
			(size 0 0)
			(layers "F.Cu" "F.Mask" "F.Paste")
			(net "P3V3_AUX")
		)
	)
	(footprint ""
		(layer "F.Cu")
		(at 197.366382 -404.113238 -90)
		(property "Reference" "C3990"
			(at 0 0 270)
			(layer "F.SilkS")
			(hide yes)
			(effects
				(font
					(size 1.27 1.27)
				)
			)
		)
		(property "Value" ""
			(at 0 0 270)
			(layer "F.Fab")
			(effects
				(font
					(size 1.27 1.27)
				)
			)
		)
		(duplicate_pad_numbers_are_jumpers no)
		(fp_line
			(start -0.7874 0.4064)
			(end -0.7874 -0.4064)
			(stroke
				(width 0.1524)
				(type default)
			)
			(layer "F.SilkS")
		)
		(fp_line
			(start 0.7874 0.4064)
			(end -0.7874 0.4064)
			(stroke
				(width 0.1524)
				(type default)
			)
			(layer "F.SilkS")
		)
		(fp_line
			(start -0.7874 -0.4064)
			(end 0.7874 -0.4064)
			(stroke
				(width 0.1524)
				(type default)
			)
			(layer "F.SilkS")
		)
		(fp_line
			(start 0.7874 -0.4064)
			(end 0.7874 0.4064)
			(stroke
				(width 0.1524)
				(type default)
			)
			(layer "F.SilkS")
		)
		(fp_line
			(start -0.67945 0.3048)
			(end -0.67945 -0.305054)
			(stroke
				(width 0.1)
				(type default)
			)
			(layer "F.Fab")
		)
		(fp_line
			(start -0.12065 0.3048)
			(end -0.67945 0.3048)
			(stroke
				(width 0.1)
				(type default)
			)
			(layer "F.Fab")
		)
		(fp_line
			(start 0.120396 0.3048)
			(end 0.120396 0.2794)
			(stroke
				(width 0.1)
				(type default)
			)
			(layer "F.Fab")
		)
		(fp_line
			(start 0.67945 0.3048)
			(end 0.120396 0.3048)
			(stroke
				(width 0.1)
				(type default)
			)
			(layer "F.Fab")
		)
		(fp_line
			(start -0.12065 0.2794)
			(end -0.12065 0.3048)
			(stroke
				(width 0.1)
				(type default)
			)
			(layer "F.Fab")
		)
		(fp_line
			(start 0.120396 0.2794)
			(end -0.12065 0.2794)
			(stroke
				(width 0.1)
				(type default)
			)
			(layer "F.Fab")
		)
		(fp_line
			(start -0.12065 -0.2794)
			(end 0.12065 -0.2794)
			(stroke
				(width 0.1)
				(type default)
			)
			(layer "F.Fab")
		)
		(fp_line
			(start 0.12065 -0.2794)
			(end 0.12065 -0.3048)
			(stroke
				(width 0.1)
				(type default)
			)
			(layer "F.Fab")
		)
		(fp_line
			(start 0.12065 -0.3048)
			(end 0.67945 -0.3048)
			(stroke
				(width 0.1)
				(type default)
			)
			(layer "F.Fab")
		)
		(fp_line
			(start 0.67945 -0.3048)
			(end 0.67945 0.3048)
			(stroke
				(width 0.1)
				(type default)
			)
			(layer "F.Fab")
		)
		(fp_line
			(start -0.67945 -0.305054)
			(end -0.12065 -0.305054)
			(stroke
				(width 0.1)
				(type default)
			)
			(layer "F.Fab")
		)
		(fp_line
			(start -0.12065 -0.305054)
			(end -0.12065 -0.2794)
			(stroke
				(width 0.1)
				(type default)
			)
			(layer "F.Fab")
		)
		(pad "1" smd circle
			(at -0.40005 0 270)
			(size 0 0)
			(layers "F.Cu" "F.Mask" "F.Paste")
			(net "GND")
		)
		(pad "2" smd circle
			(at 0.40005 0 270)
			(size 0 0)
			(layers "F.Cu" "F.Mask" "F.Paste")
			(net "HSC_P12V_EN")
		)
	)
	(footprint ""
		(layer "F.Cu")
		(at 142.368016 -55.083456)
		(property "Reference" "PC313"
			(at 0 0 0)
			(layer "F.SilkS")
			(hide yes)
			(effects
				(font
					(size 1.27 1.27)
				)
			)
		)
		(property "Value" ""
			(at 0 0 0)
			(layer "F.Fab")
			(effects
				(font
					(size 1.27 1.27)
				)
			)
		)
		(duplicate_pad_numbers_are_jumpers no)
		(fp_line
			(start -0.7874 -0.4064)
			(end 0.7874 -0.4064)
			(stroke
				(width 0.1524)
				(type default)
			)
			(layer "F.SilkS")
		)
		(fp_line
			(start -0.7874 0.4064)
			(end -0.7874 -0.4064)
			(stroke
				(width 0.1524)
				(type default)
			)
			(layer "F.SilkS")
		)
		(fp_line
			(start 0.7874 -0.4064)
			(end 0.7874 0.4064)
			(stroke
				(width 0.1524)
				(type default)
			)
			(layer "F.SilkS")
		)
		(fp_line
			(start 0.7874 0.4064)
			(end -0.7874 0.4064)
			(stroke
				(width 0.1524)
				(type default)
			)
			(layer "F.SilkS")
		)
		(fp_line
			(start -0.67945 -0.305054)
			(end -0.12065 -0.305054)
			(stroke
				(width 0.1)
				(type default)
			)
			(layer "F.Fab")
		)
		(fp_line
			(start -0.67945 0.3048)
			(end -0.67945 -0.305054)
			(stroke
				(width 0.1)
				(type default)
			)
			(layer "F.Fab")
		)
		(fp_line
			(start -0.12065 -0.305054)
			(end -0.12065 -0.2794)
			(stroke
				(width 0.1)
				(type default)
			)
			(layer "F.Fab")
		)
		(fp_line
			(start -0.12065 -0.2794)
			(end 0.12065 -0.2794)
			(stroke
				(width 0.1)
				(type default)
			)
			(layer "F.Fab")
		)
		(fp_line
			(start -0.12065 0.2794)
			(end -0.12065 0.3048)
			(stroke
				(width 0.1)
				(type default)
			)
			(layer "F.Fab")
		)
		(fp_line
			(start -0.12065 0.3048)
			(end -0.67945 0.3048)
			(stroke
				(width 0.1)
				(type default)
			)
			(layer "F.Fab")
		)
		(fp_line
			(start 0.120396 0.2794)
			(end -0.12065 0.2794)
			(stroke
				(width 0.1)
				(type default)
			)
			(layer "F.Fab")
		)
		(fp_line
			(start 0.120396 0.3048)
			(end 0.120396 0.2794)
			(stroke
				(width 0.1)
				(type default)
			)
			(layer "F.Fab")
		)
		(fp_line
			(start 0.12065 -0.3048)
			(end 0.67945 -0.3048)
			(stroke
				(width 0.1)
				(type default)
			)
			(layer "F.Fab")
		)
		(fp_line
			(start 0.12065 -0.2794)
			(end 0.12065 -0.3048)
			(stroke
				(width 0.1)
				(type default)
			)
			(layer "F.Fab")
		)
		(fp_line
			(start 0.67945 -0.3048)
			(end 0.67945 0.3048)
			(stroke
				(width 0.1)
				(type default)
			)
			(layer "F.Fab")
		)
		(fp_line
			(start 0.67945 0.3048)
			(end 0.120396 0.3048)
			(stroke
				(width 0.1)
				(type default)
			)
			(layer "F.Fab")
		)
		(pad "1" smd circle
			(at -0.40005 0)
			(size 0 0)
			(layers "F.Cu" "F.Mask" "F.Paste")
			(net "P5V_AUX")
		)
		(pad "2" smd circle
			(at 0.40005 0)
			(size 0 0)
			(layers "F.Cu" "F.Mask" "F.Paste")
			(net "GND")
		)
	)
	(footprint ""
		(layer "F.Cu")
		(at 261.997952 -215.194388 180)
		(property "Reference" "R6646"
			(at 0 0 180)
			(layer "F.SilkS")
			(hide yes)
			(effects
				(font
					(size 1.27 1.27)
				)
			)
		)
		(property "Value" ""
			(at 0 0 180)
			(layer "F.Fab")
			(effects
				(font
					(size 1.27 1.27)
				)
			)
		)
		(duplicate_pad_numbers_are_jumpers no)
		(fp_line
			(start 0.7874 0.4064)
			(end -0.7874 0.4064)
			(stroke
				(width 0.1524)
				(type default)
			)
			(layer "F.SilkS")
		)
		(fp_line
			(start 0.7874 -0.4064)
			(end 0.7874 0.4064)
			(stroke
				(width 0.1524)
				(type default)
			)
			(layer "F.SilkS")
		)
		(fp_line
			(start -0.7874 0.4064)
			(end -0.7874 -0.4064)
			(stroke
				(width 0.1524)
				(type default)
			)
			(layer "F.SilkS")
		)
		(fp_line
			(start -0.7874 -0.4064)
			(end 0.7874 -0.4064)
			(stroke
				(width 0.1524)
				(type default)
			)
			(layer "F.SilkS")
		)
		(fp_line
			(start 0.67945 0.3048)
			(end 0.120396 0.3048)
			(stroke
				(width 0.1)
				(type default)
			)
			(layer "F.Fab")
		)
		(fp_line
			(start 0.67945 -0.3048)
			(end 0.67945 0.3048)
			(stroke
				(width 0.1)
				(type default)
			)
			(layer "F.Fab")
		)
		(fp_line
			(start 0.12065 -0.2794)
			(end 0.12065 -0.3048)
			(stroke
				(width 0.1)
				(type default)
			)
			(layer "F.Fab")
		)
		(fp_line
			(start 0.12065 -0.3048)
			(end 0.67945 -0.3048)
			(stroke
				(width 0.1)
				(type default)
			)
			(layer "F.Fab")
		)
		(fp_line
			(start 0.120396 0.3048)
			(end 0.120396 0.2794)
			(stroke
				(width 0.1)
				(type default)
			)
			(layer "F.Fab")
		)
		(fp_line
			(start 0.120396 0.2794)
			(end -0.12065 0.2794)
			(stroke
				(width 0.1)
				(type default)
			)
			(layer "F.Fab")
		)
		(fp_line
			(start -0.12065 0.3048)
			(end -0.67945 0.3048)
			(stroke
				(width 0.1)
				(type default)
			)
			(layer "F.Fab")
		)
		(fp_line
			(start -0.12065 0.2794)
			(end -0.12065 0.3048)
			(stroke
				(width 0.1)
				(type default)
			)
			(layer "F.Fab")
		)
		(fp_line
			(start -0.12065 -0.2794)
			(end 0.12065 -0.2794)
			(stroke
				(width 0.1)
				(type default)
			)
			(layer "F.Fab")
		)
		(fp_line
			(start -0.12065 -0.305054)
			(end -0.12065 -0.2794)
			(stroke
				(width 0.1)
				(type default)
			)
			(layer "F.Fab")
		)
		(fp_line
			(start -0.67945 0.3048)
			(end -0.67945 -0.305054)
			(stroke
				(width 0.1)
				(type default)
			)
			(layer "F.Fab")
		)
		(fp_line
			(start -0.67945 -0.305054)
			(end -0.12065 -0.305054)
			(stroke
				(width 0.1)
				(type default)
			)
			(layer "F.Fab")
		)
		(pad "1" smd circle
			(at -0.40005 0 180)
			(size 0 0)
			(layers "F.Cu" "F.Mask" "F.Paste")
			(net "HSC_D_OC_BIC_N")
		)
		(pad "2" smd circle
			(at 0.40005 0 180)
			(size 0 0)
			(layers "F.Cu" "F.Mask" "F.Paste")
			(net "HSC_D_OC_BUF_R_N")
		)
	)
	(footprint ""
		(layer "F.Cu")
		(at 8.049768 -158.828994 180)
		(property "Reference" "R5830"
			(at 0 0 180)
			(layer "F.SilkS")
			(hide yes)
			(effects
				(font
					(size 1.27 1.27)
				)
			)
		)
		(property "Value" ""
			(at 0 0 180)
			(layer "F.Fab")
			(effects
				(font
					(size 1.27 1.27)
				)
			)
		)
		(duplicate_pad_numbers_are_jumpers no)
		(fp_line
			(start 0.7874 0.4064)
			(end -0.7874 0.4064)
			(stroke
				(width 0.1524)
				(type default)
			)
			(layer "F.SilkS")
		)
		(fp_line
			(start 0.7874 -0.4064)
			(end 0.7874 0.4064)
			(stroke
				(width 0.1524)
				(type default)
			)
			(layer "F.SilkS")
		)
		(fp_line
			(start -0.7874 0.4064)
			(end -0.7874 -0.4064)
			(stroke
				(width 0.1524)
				(type default)
			)
			(layer "F.SilkS")
		)
		(fp_line
			(start -0.7874 -0.4064)
			(end 0.7874 -0.4064)
			(stroke
				(width 0.1524)
				(type default)
			)
			(layer "F.SilkS")
		)
		(fp_line
			(start 0.67945 0.3048)
			(end 0.120396 0.3048)
			(stroke
				(width 0.1)
				(type default)
			)
			(layer "F.Fab")
		)
		(fp_line
			(start 0.67945 -0.3048)
			(end 0.67945 0.3048)
			(stroke
				(width 0.1)
				(type default)
			)
			(layer "F.Fab")
		)
		(fp_line
			(start 0.12065 -0.2794)
			(end 0.12065 -0.3048)
			(stroke
				(width 0.1)
				(type default)
			)
			(layer "F.Fab")
		)
		(fp_line
			(start 0.12065 -0.3048)
			(end 0.67945 -0.3048)
			(stroke
				(width 0.1)
				(type default)
			)
			(layer "F.Fab")
		)
		(fp_line
			(start 0.120396 0.3048)
			(end 0.120396 0.2794)
			(stroke
				(width 0.1)
				(type default)
			)
			(layer "F.Fab")
		)
		(fp_line
			(start 0.120396 0.2794)
			(end -0.12065 0.2794)
			(stroke
				(width 0.1)
				(type default)
			)
			(layer "F.Fab")
		)
		(fp_line
			(start -0.12065 0.3048)
			(end -0.67945 0.3048)
			(stroke
				(width 0.1)
				(type default)
			)
			(layer "F.Fab")
		)
		(fp_line
			(start -0.12065 0.2794)
			(end -0.12065 0.3048)
			(stroke
				(width 0.1)
				(type default)
			)
			(layer "F.Fab")
		)
		(fp_line
			(start -0.12065 -0.2794)
			(end 0.12065 -0.2794)
			(stroke
				(width 0.1)
				(type default)
			)
			(layer "F.Fab")
		)
		(fp_line
			(start -0.12065 -0.305054)
			(end -0.12065 -0.2794)
			(stroke
				(width 0.1)
				(type default)
			)
			(layer "F.Fab")
		)
		(fp_line
			(start -0.67945 0.3048)
			(end -0.67945 -0.305054)
			(stroke
				(width 0.1)
				(type default)
			)
			(layer "F.Fab")
		)
		(fp_line
			(start -0.67945 -0.305054)
			(end -0.12065 -0.305054)
			(stroke
				(width 0.1)
				(type default)
			)
			(layer "F.Fab")
		)
		(pad "1" smd circle
			(at -0.40005 0 180)
			(size 0 0)
			(layers "F.Cu" "F.Mask" "F.Paste")
			(net "PWRGD_P12V_NIC0_CO")
		)
		(pad "2" smd circle
			(at 0.40005 0 180)
			(size 0 0)
			(layers "F.Cu" "F.Mask" "F.Paste")
			(net "PWRGD_P12V_NIC0_R")
		)
	)
	(footprint ""
		(layer "F.Cu")
		(at 353.822 -165.608)
		(property "Reference" "R4776"
			(at 0 0 0)
			(layer "F.SilkS")
			(hide yes)
			(effects
				(font
					(size 1.27 1.27)
				)
			)
		)
		(property "Value" ""
			(at 0 0 0)
			(layer "F.Fab")
			(effects
				(font
					(size 1.27 1.27)
				)
			)
		)
		(duplicate_pad_numbers_are_jumpers no)
		(fp_line
			(start -0.7874 -0.4064)
			(end 0.7874 -0.4064)
			(stroke
				(width 0.1524)
				(type default)
			)
			(layer "F.SilkS")
		)
		(fp_line
			(start -0.7874 0.4064)
			(end -0.7874 -0.4064)
			(stroke
				(width 0.1524)
				(type default)
			)
			(layer "F.SilkS")
		)
		(fp_line
			(start 0.7874 -0.4064)
			(end 0.7874 0.4064)
			(stroke
				(width 0.1524)
				(type default)
			)
			(layer "F.SilkS")
		)
		(fp_line
			(start 0.7874 0.4064)
			(end -0.7874 0.4064)
			(stroke
				(width 0.1524)
				(type default)
			)
			(layer "F.SilkS")
		)
		(fp_line
			(start -0.67945 -0.305054)
			(end -0.12065 -0.305054)
			(stroke
				(width 0.1)
				(type default)
			)
			(layer "F.Fab")
		)
		(fp_line
			(start -0.67945 0.3048)
			(end -0.67945 -0.305054)
			(stroke
				(width 0.1)
				(type default)
			)
			(layer "F.Fab")
		)
		(fp_line
			(start -0.12065 -0.305054)
			(end -0.12065 -0.2794)
			(stroke
				(width 0.1)
				(type default)
			)
			(layer "F.Fab")
		)
		(fp_line
			(start -0.12065 -0.2794)
			(end 0.12065 -0.2794)
			(stroke
				(width 0.1)
				(type default)
			)
			(layer "F.Fab")
		)
		(fp_line
			(start -0.12065 0.2794)
			(end -0.12065 0.3048)
			(stroke
				(width 0.1)
				(type default)
			)
			(layer "F.Fab")
		)
		(fp_line
			(start -0.12065 0.3048)
			(end -0.67945 0.3048)
			(stroke
				(width 0.1)
				(type default)
			)
			(layer "F.Fab")
		)
		(fp_line
			(start 0.120396 0.2794)
			(end -0.12065 0.2794)
			(stroke
				(width 0.1)
				(type default)
			)
			(layer "F.Fab")
		)
		(fp_line
			(start 0.120396 0.3048)
			(end 0.120396 0.2794)
			(stroke
				(width 0.1)
				(type default)
			)
			(layer "F.Fab")
		)
		(fp_line
			(start 0.12065 -0.3048)
			(end 0.67945 -0.3048)
			(stroke
				(width 0.1)
				(type default)
			)
			(layer "F.Fab")
		)
		(fp_line
			(start 0.12065 -0.2794)
			(end 0.12065 -0.3048)
			(stroke
				(width 0.1)
				(type default)
			)
			(layer "F.Fab")
		)
		(fp_line
			(start 0.67945 -0.3048)
			(end 0.67945 0.3048)
			(stroke
				(width 0.1)
				(type default)
			)
			(layer "F.Fab")
		)
		(fp_line
			(start 0.67945 0.3048)
			(end 0.120396 0.3048)
			(stroke
				(width 0.1)
				(type default)
			)
			(layer "F.Fab")
		)
		(pad "1" smd circle
			(at -0.40005 0)
			(size 0 0)
			(layers "F.Cu" "F.Mask" "F.Paste")
			(net "PRSNT_NIC5_FPGA_PCA9555_N")
		)
		(pad "2" smd circle
			(at 0.40005 0)
			(size 0 0)
			(layers "F.Cu" "F.Mask" "F.Paste")
			(net "PRSNT_NIC5_FPGA_R_N")
		)
	)
)
